FILE_TYPE = CONNECTIVITY;
{Allegro Design Entry HDL 16.6-p007 (v16-6-112F) 10/10/2012}
"PAGE_NUMBER" = 50;
0"NC";
1"M_D_DQS_DN<17:0>";
2"M_D_MA<17:0>";
3"M_D_DQS_DP<17:0>";
4"M_D_DQ<63:0>";
5"M_D_BA<1:0>";
6"M_D_BG<1:0>";
7"M_D_CS_N<7:0>";
8"M_D_CLK_DP<3:0>";
9"M_D_CLK_DN<3:0>";
10"M_D_CKE<3:0>";
11"M_D_ODT<3:0>";
12"M_D_ECC<7:0>";
13"GND\g";
14"PVPP_DEF\g";
15"GND\g";
16"GND\g";
17"P12V_NVDIMM_DEF\g";
18"GND\g";
19"PVPP_DEF\g";
20"PVTT_DEF\g";
21"PVDDQ_DEF\g";
22"M_D_VREF";
23"FM_DIMM_EVENT_COD_N";
24"TP_CH_D_DIMM_D1_RFU_2";
25"TP_CH_D_DIMM_D1_RFU_0";
26"TP_CH_D_DIMM_D1_RFU_1";
27"M_D_ALERT_N";
28"M_D_ACT_N";
29"SMB_DDR_DEF_VPP_SDA";
30"SMB_DDR_DEF_VPP_SCL";
31"FM_ADR_COMPLETE_DEF_N";
32"M_D_DQ<8>";
33"M_D_DQ<7>";
34"M_D_DQ<6>";
35"M_D_DQ<1>";
36"M_D_DQ<0>";
37"M_D_DQ<2>";
38"M_D_DQ<3>";
39"M_D_DQ<4>";
40"M_D_DQ<5>";
41"M_D_ECC<4>";
42"M_D_ECC<3>";
43"M_D_ECC<2>";
44"M_D_ECC<1>";
45"M_D_ECC<0>";
46"M_D_PAR";
47"M_DEF_RST_N";
48"M_D_ECC<6>";
49"M_D_ECC<5>";
50"M_D_CKE<3>";
51"M_D_ECC<7>";
52"M_D_ODT<2>";
53"M_D_ODT<3>";
54"M_D_CKE<2>";
55"M_D_CLK_DN<3>";
56"M_D_CLK_DP<2>";
57"M_D_CS_N<7>";
58"M_D_CS_N<6>";
59"M_D_CS_N<5>";
60"M_D_CLK_DN<2>";
61"M_D_CLK_DP<3>";
62"M_D_CS_N<4>";
63"M_D_C<2>";
64"M_D_BA<1>";
65"M_D_MA<0>";
66"M_D_MA<1>";
67"M_D_MA<3>";
68"M_D_BG<0>";
69"M_D_BG<1>";
70"M_D_BA<0>";
71"M_D_MA<2>";
72"M_D_DQ<29>";
73"M_D_DQ<28>";
74"M_D_DQ<25>";
75"M_D_DQ<24>";
76"M_D_DQ<23>";
77"M_D_DQ<22>";
78"M_D_DQ<21>";
79"M_D_DQ<20>";
80"M_D_DQ<19>";
81"M_D_DQ<18>";
82"M_D_DQ<16>";
83"M_D_DQ<14>";
84"M_D_DQ<13>";
85"M_D_DQ<12>";
86"M_D_DQ<11>";
87"M_D_DQ<10>";
88"M_D_DQ<9>";
89"M_D_DQ<27>";
90"M_D_DQ<26>";
91"M_D_DQ<15>";
92"M_D_DQ<17>";
93"M_D_DQ<46>";
94"M_D_DQ<45>";
95"M_D_DQ<44>";
96"M_D_DQ<43>";
97"M_D_DQ<42>";
98"M_D_DQ<41>";
99"M_D_DQ<40>";
100"M_D_DQ<39>";
101"M_D_DQ<37>";
102"M_D_DQ<34>";
103"M_D_DQ<33>";
104"M_D_DQ<32>";
105"M_D_DQ<31>";
106"M_D_DQ<30>";
107"M_D_DQ<35>";
108"M_D_DQ<36>";
109"M_D_DQ<38>";
110"M_D_DQ<49>";
111"M_D_DQ<48>";
112"M_D_DQ<47>";
113"M_D_DQS_DP<0>";
114"M_D_DQS_DP<1>";
115"M_D_DQS_DP<2>";
116"M_D_DQS_DP<3>";
117"M_D_DQS_DP<4>";
118"M_D_DQS_DP<5>";
119"M_D_DQS_DP<6>";
120"M_D_DQS_DP<7>";
121"M_D_DQS_DP<8>";
122"M_D_DQS_DP<9>";
123"M_D_MA<12>";
124"M_D_MA<13>";
125"M_D_MA<4>";
126"M_D_MA<5>";
127"M_D_MA<6>";
128"M_D_MA<7>";
129"M_D_MA<8>";
130"M_D_MA<9>";
131"M_D_MA<10>";
132"M_D_MA<11>";
133"M_D_MA<14>";
134"M_D_MA<17>";
135"M_D_MA<15>";
136"M_D_MA<16>";
137"M_D_DQ<63>";
138"M_D_DQ<62>";
139"M_D_DQ<61>";
140"M_D_DQ<60>";
141"M_D_DQ<59>";
142"M_D_DQ<56>";
143"M_D_DQ<55>";
144"M_D_DQ<57>";
145"M_D_DQ<58>";
146"M_D_DQ<54>";
147"M_D_DQ<53>";
148"M_D_DQ<52>";
149"M_D_DQ<51>";
150"M_D_DQ<50>";
151"M_D_DQS_DP<10>";
152"M_D_DQS_DP<11>";
153"M_D_DQS_DP<12>";
154"M_D_DQS_DP<13>";
155"M_D_DQS_DP<14>";
156"M_D_DQS_DP<15>";
157"M_D_DQS_DP<16>";
158"M_D_DQS_DP<17>";
159"M_D_DQS_DN<0>";
160"M_D_DQS_DN<10>";
161"M_D_DQS_DN<11>";
162"M_D_DQS_DN<12>";
163"M_D_DQS_DN<13>";
164"M_D_DQS_DN<14>";
165"M_D_DQS_DN<15>";
166"M_D_DQS_DN<16>";
167"M_D_DQS_DN<17>";
168"M_D_DQS_DN<1>";
169"M_D_DQS_DN<2>";
170"M_D_DQS_DN<3>";
171"M_D_DQS_DN<4>";
172"M_D_DQS_DN<5>";
173"M_D_DQS_DN<6>";
174"M_D_DQS_DN<7>";
175"M_D_DQS_DN<8>";
176"M_D_DQS_DN<9>";
%"GND"
"1","(5950,750)","2","mstr_symbols","I1";
;
HDL_POWER"GND"
ROOM"DDR4_CH_B"
BODY_TYPE"PLUMBING"
SIZE"1B"
CDS_LIB"mstr_symbols"
BOM_COST"MEM"
VOLTAGE"0";
"A\NAC"13;
%"TAP"
"6","(4350,4350)","2","mstr_standard","I10";
;
HDL_TAP"TRUE"
BODY_TYPE"PLUMBING"
CDS_LIB"mstr_standard";
"B \NAC \NWC"1;
"S \NAC"
BN"13"163;
%"TAP"
"6","(1700,3050)","2","mstr_standard","I100";
;
HDL_TAP"TRUE"
BODY_TYPE"PLUMBING"
CDS_LIB"mstr_standard";
"B \NAC \NWC"4;
"S \NAC"
BN"29"72;
%"TAP"
"6","(1700,2850)","2","mstr_standard","I101";
;
HDL_TAP"TRUE"
BODY_TYPE"PLUMBING"
CDS_LIB"mstr_standard";
"B \NAC \NWC"4;
"S \NAC"
BN"25"74;
%"TAP"
"6","(1700,2800)","2","mstr_standard","I102";
;
HDL_TAP"TRUE"
BODY_TYPE"PLUMBING"
CDS_LIB"mstr_standard";
"B \NAC \NWC"4;
"S \NAC"
BN"24"75;
%"TAP"
"6","(1700,2900)","2","mstr_standard","I103";
;
HDL_TAP"TRUE"
BODY_TYPE"PLUMBING"
CDS_LIB"mstr_standard";
"B \NAC \NWC"4;
"S \NAC"
BN"26"90;
%"TAP"
"6","(1700,2950)","2","mstr_standard","I104";
;
HDL_TAP"TRUE"
BODY_TYPE"PLUMBING"
CDS_LIB"mstr_standard";
"B \NAC \NWC"4;
"S \NAC"
BN"27"89;
%"TAP"
"6","(1700,3000)","2","mstr_standard","I105";
;
HDL_TAP"TRUE"
BODY_TYPE"PLUMBING"
CDS_LIB"mstr_standard";
"B \NAC \NWC"4;
"S \NAC"
BN"28"73;
%"TAP"
"6","(1700,2650)","2","mstr_standard","I106";
;
HDL_TAP"TRUE"
BODY_TYPE"PLUMBING"
CDS_LIB"mstr_standard";
"B \NAC \NWC"4;
"S \NAC"
BN"21"78;
%"TAP"
"6","(1700,2600)","2","mstr_standard","I107";
;
HDL_TAP"TRUE"
BODY_TYPE"PLUMBING"
CDS_LIB"mstr_standard";
"B \NAC \NWC"4;
"S \NAC"
BN"20"79;
%"TAP"
"6","(1700,2550)","2","mstr_standard","I108";
;
HDL_TAP"TRUE"
BODY_TYPE"PLUMBING"
CDS_LIB"mstr_standard";
"B \NAC \NWC"4;
"S \NAC"
BN"19"80;
%"TAP"
"6","(1700,2700)","2","mstr_standard","I109";
;
HDL_TAP"TRUE"
BODY_TYPE"PLUMBING"
CDS_LIB"mstr_standard";
"B \NAC \NWC"4;
"S \NAC"
BN"22"77;
%"TAP"
"6","(4350,4450)","2","mstr_standard","I11";
;
HDL_TAP"TRUE"
BODY_TYPE"PLUMBING"
CDS_LIB"mstr_standard";
"B \NAC \NWC"1;
"S \NAC"
BN"14"164;
%"TAP"
"6","(1700,2750)","2","mstr_standard","I110";
;
HDL_TAP"TRUE"
BODY_TYPE"PLUMBING"
CDS_LIB"mstr_standard";
"B \NAC \NWC"4;
"S \NAC"
BN"23"76;
%"TAP"
"6","(1700,2300)","2","mstr_standard","I111";
;
HDL_TAP"TRUE"
BODY_TYPE"PLUMBING"
CDS_LIB"mstr_standard";
"B \NAC \NWC"4;
"S \NAC"
BN"14"83;
%"TAP"
"6","(1700,2350)","2","mstr_standard","I112";
;
HDL_TAP"TRUE"
BODY_TYPE"PLUMBING"
CDS_LIB"mstr_standard";
"B \NAC \NWC"4;
"S \NAC"
BN"15"91;
%"TAP"
"6","(1700,2400)","2","mstr_standard","I113";
;
HDL_TAP"TRUE"
BODY_TYPE"PLUMBING"
CDS_LIB"mstr_standard";
"B \NAC \NWC"4;
"S \NAC"
BN"16"82;
%"TAP"
"6","(1700,2500)","2","mstr_standard","I114";
;
HDL_TAP"TRUE"
BODY_TYPE"PLUMBING"
CDS_LIB"mstr_standard";
"B \NAC \NWC"4;
"S \NAC"
BN"18"81;
%"TAP"
"6","(1700,2450)","2","mstr_standard","I115";
;
HDL_TAP"TRUE"
BODY_TYPE"PLUMBING"
CDS_LIB"mstr_standard";
"B \NAC \NWC"4;
"S \NAC"
BN"17"92;
%"TAP"
"6","(1700,2100)","2","mstr_standard","I116";
;
HDL_TAP"TRUE"
BODY_TYPE"PLUMBING"
CDS_LIB"mstr_standard";
"B \NAC \NWC"4;
"S \NAC"
BN"10"87;
%"TAP"
"6","(1700,2050)","2","mstr_standard","I117";
;
HDL_TAP"TRUE"
BODY_TYPE"PLUMBING"
CDS_LIB"mstr_standard";
"B \NAC \NWC"4;
"S \NAC"
BN"9"88;
%"TAP"
"6","(1700,2150)","2","mstr_standard","I118";
;
HDL_TAP"TRUE"
BODY_TYPE"PLUMBING"
CDS_LIB"mstr_standard";
"B \NAC \NWC"4;
"S \NAC"
BN"11"86;
%"TAP"
"6","(1700,2200)","2","mstr_standard","I119";
;
HDL_TAP"TRUE"
BODY_TYPE"PLUMBING"
CDS_LIB"mstr_standard";
"B \NAC \NWC"4;
"S \NAC"
BN"12"85;
%"TAP"
"6","(4350,4250)","2","mstr_standard","I12";
;
HDL_TAP"TRUE"
BODY_TYPE"PLUMBING"
CDS_LIB"mstr_standard";
"B \NAC \NWC"1;
"S \NAC"
BN"12"162;
%"TAP"
"6","(1700,2250)","2","mstr_standard","I120";
;
HDL_TAP"TRUE"
BODY_TYPE"PLUMBING"
CDS_LIB"mstr_standard";
"B \NAC \NWC"4;
"S \NAC"
BN"13"84;
%"TAP"
"6","(200,4050)","0","mstr_standard","I121";
;
HDL_TAP"TRUE"
BODY_TYPE"PLUMBING"
CDS_LIB"mstr_standard";
"B \NAC \NWC"2;
"S \NAC"
BN"3"67;
%"TAP"
"6","(200,3900)","0","mstr_standard","I122";
;
HDL_TAP"TRUE"
BODY_TYPE"PLUMBING"
CDS_LIB"mstr_standard";
"B \NAC \NWC"2;
"S \NAC"
BN"0"65;
%"TAP"
"6","(200,3950)","0","mstr_standard","I123";
;
HDL_TAP"TRUE"
BODY_TYPE"PLUMBING"
CDS_LIB"mstr_standard";
"B \NAC \NWC"2;
"S \NAC"
BN"1"66;
%"TAP"
"6","(200,4000)","0","mstr_standard","I124";
;
HDL_TAP"TRUE"
BODY_TYPE"PLUMBING"
CDS_LIB"mstr_standard";
"B \NAC \NWC"2;
"S \NAC"
BN"2"71;
%"TAP"
"6","(200,3800)","0","mstr_standard","I125";
;
HDL_TAP"TRUE"
BODY_TYPE"PLUMBING"
CDS_LIB"mstr_standard";
"B \NAC \NWC"5;
"S \NAC"
BN"1"64;
%"TAP"
"6","(200,3650)","0","mstr_standard","I126";
;
HDL_TAP"TRUE"
BODY_TYPE"PLUMBING"
CDS_LIB"mstr_standard";
"B \NAC \NWC"6;
"S \NAC"
BN"0"68;
%"TAP"
"6","(200,3750)","0","mstr_standard","I127";
;
HDL_TAP"TRUE"
BODY_TYPE"PLUMBING"
CDS_LIB"mstr_standard";
"B \NAC \NWC"5;
"S \NAC"
BN"0"70;
%"TAP"
"6","(200,3700)","0","mstr_standard","I128";
;
HDL_TAP"TRUE"
BODY_TYPE"PLUMBING"
CDS_LIB"mstr_standard";
"B \NAC \NWC"6;
"S \NAC"
BN"1"69;
%"TAP"
"6","(200,3550)","0","mstr_standard","I129";
;
HDL_TAP"TRUE"
BODY_TYPE"PLUMBING"
CDS_LIB"mstr_standard";
"B \NAC \NWC"8;
"S \NAC"
BN"3"61;
%"TAP"
"6","(4350,4150)","2","mstr_standard","I13";
;
HDL_TAP"TRUE"
BODY_TYPE"PLUMBING"
CDS_LIB"mstr_standard";
"B \NAC \NWC"1;
"S \NAC"
BN"11"161;
%"TAP"
"6","(200,3450)","0","mstr_standard","I130";
;
HDL_TAP"TRUE"
BODY_TYPE"PLUMBING"
CDS_LIB"mstr_standard";
"B \NAC \NWC"8;
"S \NAC"
BN"2"56;
%"TAP"
"6","(200,3250)","0","mstr_standard","I131";
;
HDL_TAP"TRUE"
BODY_TYPE"PLUMBING"
CDS_LIB"mstr_standard";
"B \NAC \NWC"7;
"S \NAC"
BN"7"57;
%"TAP"
"6","(200,3200)","0","mstr_standard","I132";
;
HDL_TAP"TRUE"
BODY_TYPE"PLUMBING"
CDS_LIB"mstr_standard";
"B \NAC \NWC"7;
"S \NAC"
BN"6"58;
%"TAP"
"6","(200,3150)","0","mstr_standard","I133";
;
HDL_TAP"TRUE"
BODY_TYPE"PLUMBING"
CDS_LIB"mstr_standard";
"B \NAC \NWC"7;
"S \NAC"
BN"5"59;
%"TAP"
"6","(200,3100)","0","mstr_standard","I134";
;
HDL_TAP"TRUE"
BODY_TYPE"PLUMBING"
CDS_LIB"mstr_standard";
"B \NAC \NWC"7;
"S \NAC"
BN"4"62;
%"TAP"
"6","(0,3500)","0","mstr_standard","I135";
;
HDL_TAP"TRUE"
BODY_TYPE"PLUMBING"
CDS_LIB"mstr_standard";
"B \NAC \NWC"9;
"S \NAC"
BN"3"55;
%"TAP"
"6","(0,3400)","0","mstr_standard","I136";
;
HDL_TAP"TRUE"
BODY_TYPE"PLUMBING"
CDS_LIB"mstr_standard";
"B \NAC \NWC"9;
"S \NAC"
BN"2"60;
%"TAP"
"6","(200,2800)","0","mstr_standard","I137";
;
HDL_TAP"TRUE"
BODY_TYPE"PLUMBING"
CDS_LIB"mstr_standard";
"B \NAC \NWC"11;
"S \NAC"
BN"2"52;
%"TAP"
"6","(200,2950)","0","mstr_standard","I138";
;
HDL_TAP"TRUE"
BODY_TYPE"PLUMBING"
CDS_LIB"mstr_standard";
"B \NAC \NWC"10;
"S \NAC"
BN"2"54;
%"TAP"
"6","(200,3000)","0","mstr_standard","I139";
;
HDL_TAP"TRUE"
BODY_TYPE"PLUMBING"
CDS_LIB"mstr_standard";
"B \NAC \NWC"10;
"S \NAC"
BN"3"50;
%"TAP"
"6","(4100,4500)","2","mstr_standard","I14";
;
HDL_TAP"TRUE"
BODY_TYPE"PLUMBING"
CDS_LIB"mstr_standard";
"B \NAC \NWC"3;
"S \NAC"
BN"14"155;
%"TAP"
"6","(200,2850)","0","mstr_standard","I140";
;
HDL_TAP"TRUE"
BODY_TYPE"PLUMBING"
CDS_LIB"mstr_standard";
"B \NAC \NWC"11;
"S \NAC"
BN"3"53;
%"TAP"
"6","(200,2650)","0","mstr_standard","I141";
;
HDL_TAP"TRUE"
BODY_TYPE"PLUMBING"
CDS_LIB"mstr_standard";
"B \NAC \NWC"12;
"S \NAC"
BN"6"48;
%"TAP"
"6","(200,2700)","0","mstr_standard","I142";
;
HDL_TAP"TRUE"
BODY_TYPE"PLUMBING"
CDS_LIB"mstr_standard";
"B \NAC \NWC"12;
"S \NAC"
BN"7"51;
%"TAP"
"6","(200,2600)","0","mstr_standard","I143";
;
HDL_TAP"TRUE"
BODY_TYPE"PLUMBING"
CDS_LIB"mstr_standard";
"B \NAC \NWC"12;
"S \NAC"
BN"5"49;
%"TAP"
"6","(200,2550)","0","mstr_standard","I144";
;
HDL_TAP"TRUE"
BODY_TYPE"PLUMBING"
CDS_LIB"mstr_standard";
"B \NAC \NWC"12;
"S \NAC"
BN"4"41;
%"TAP"
"6","(200,2350)","0","mstr_standard","I145";
;
HDL_TAP"TRUE"
BODY_TYPE"PLUMBING"
CDS_LIB"mstr_standard";
"B \NAC \NWC"12;
"S \NAC"
BN"0"45;
%"TAP"
"6","(200,2400)","0","mstr_standard","I146";
;
HDL_TAP"TRUE"
BODY_TYPE"PLUMBING"
CDS_LIB"mstr_standard";
"B \NAC \NWC"12;
"S \NAC"
BN"1"44;
%"TAP"
"6","(200,2450)","0","mstr_standard","I147";
;
HDL_TAP"TRUE"
BODY_TYPE"PLUMBING"
CDS_LIB"mstr_standard";
"B \NAC \NWC"12;
"S \NAC"
BN"2"43;
%"TAP"
"6","(200,2500)","0","mstr_standard","I148";
;
HDL_TAP"TRUE"
BODY_TYPE"PLUMBING"
CDS_LIB"mstr_standard";
"B \NAC \NWC"12;
"S \NAC"
BN"3"42;
%"TAP"
"6","(1700,1850)","2","mstr_standard","I149";
;
HDL_TAP"TRUE"
BODY_TYPE"PLUMBING"
CDS_LIB"mstr_standard";
"B \NAC \NWC"4;
"S \NAC"
BN"5"40;
%"TAP"
"6","(4100,4400)","2","mstr_standard","I15";
;
HDL_TAP"TRUE"
BODY_TYPE"PLUMBING"
CDS_LIB"mstr_standard";
"B \NAC \NWC"3;
"S \NAC"
BN"13"154;
%"TAP"
"6","(1700,1800)","2","mstr_standard","I150";
;
HDL_TAP"TRUE"
BODY_TYPE"PLUMBING"
CDS_LIB"mstr_standard";
"B \NAC \NWC"4;
"S \NAC"
BN"4"39;
%"TAP"
"6","(1700,1950)","2","mstr_standard","I151";
;
HDL_TAP"TRUE"
BODY_TYPE"PLUMBING"
CDS_LIB"mstr_standard";
"B \NAC \NWC"4;
"S \NAC"
BN"7"33;
%"TAP"
"6","(1700,2000)","2","mstr_standard","I152";
;
HDL_TAP"TRUE"
BODY_TYPE"PLUMBING"
CDS_LIB"mstr_standard";
"B \NAC \NWC"4;
"S \NAC"
BN"8"32;
%"TAP"
"6","(1700,1900)","2","mstr_standard","I153";
;
HDL_TAP"TRUE"
BODY_TYPE"PLUMBING"
CDS_LIB"mstr_standard";
"B \NAC \NWC"4;
"S \NAC"
BN"6"34;
%"TAP"
"6","(1700,1600)","2","mstr_standard","I154";
;
HDL_TAP"TRUE"
BODY_TYPE"PLUMBING"
CDS_LIB"mstr_standard";
"B \NAC \NWC"4;
"S \NAC"
BN"0"36;
%"TAP"
"6","(1700,1700)","2","mstr_standard","I155";
;
HDL_TAP"TRUE"
BODY_TYPE"PLUMBING"
CDS_LIB"mstr_standard";
"B \NAC \NWC"4;
"S \NAC"
BN"2"37;
%"TAP"
"6","(1700,1650)","2","mstr_standard","I156";
;
HDL_TAP"TRUE"
BODY_TYPE"PLUMBING"
CDS_LIB"mstr_standard";
"B \NAC \NWC"4;
"S \NAC"
BN"1"35;
%"TAP"
"6","(1700,1750)","2","mstr_standard","I157";
;
HDL_TAP"TRUE"
BODY_TYPE"PLUMBING"
CDS_LIB"mstr_standard";
"B \NAC \NWC"4;
"S \NAC"
BN"3"38;
%"SCONN288_H44441003"
"1","(950,3100)","0","mstr_sconn","I158";
;
CDS_SEC"1"
ROOM"DDR4_CH_D"
CDS_LOCATION"J6M1"
SEC"1"
SEC_TYPE"PIP"
CDS_LIB"mstr_sconn"
BOM_COST"MEM"
PACK_TYPE"PIP"
MATERIAL"SCONN"
PART_NUMBER"H44441-003"
LOCATION"J6M1";
"DQ<63>"
$PN"280"137;
"BA<1>"
$PN"224"64;
"CK1N"
$PN"219"55;
"CK0P"
$PN"74"56;
"S3_N_C<1>"
$PN"237"57;
"S2_N_C<0>"
$PN"93"58;
"S1_N"
$PN"89"59;
"DQ<29>"
$PN"181"72;
"DQ<28>"
$PN"36"73;
"C<2>"
$PN"235"63;
"A0"
$PN"79"65;
"A1"
$PN"72"66;
"A12"
$PN"65"123;
"A13"
$PN"232"124;
"A17"
$PN"234"134;
"A3"
$PN"71"67;
"A4"
$PN"214"125;
"A5"
$PN"213"126;
"A6"
$PN"69"127;
"A7"
$PN"211"128;
"A8"
$PN"68"129;
"A9"
$PN"66"130;
"CB<6>"
$PN"54"48;
"CB<5>"
$PN"192"49;
"CB<4>"
$PN"47"41;
"CB<3>"
$PN"201"42;
"CB<2>"
$PN"56"43;
"CB<1>"
$PN"194"44;
"CB<0>"
$PN"49"45;
"CK0N"
$PN"75"60;
"CKE<1>"
$PN"203"50;
"DQ<62>"
$PN"135"138;
"DQ<61>"
$PN"273"139;
"DQ<60>"
$PN"128"140;
"DQ<59>"
$PN"282"141;
"DQ<56>"
$PN"130"142;
"DQ<55>"
$PN"269"143;
"DQ<46>"
$PN"113"93;
"DQ<45>"
$PN"251"94;
"DQ<44>"
$PN"106"95;
"DQ<43>"
$PN"260"96;
"DQ<42>"
$PN"115"97;
"DQ<41>"
$PN"253"98;
"DQ<40>"
$PN"108"99;
"DQ<39>"
$PN"247"100;
"DQ<37>"
$PN"240"101;
"DQ<34>"
$PN"104"102;
"DQ<33>"
$PN"242"103;
"DQ<32>"
$PN"97"104;
"DQ<31>"
$PN"188"105;
"DQ<30>"
$PN"43"106;
"DQ<25>"
$PN"183"74;
"DQ<24>"
$PN"38"75;
"DQ<23>"
$PN"177"76;
"DQ<22>"
$PN"32"77;
"DQ<21>"
$PN"170"78;
"DQ<20>"
$PN"25"79;
"DQ<19>"
$PN"179"80;
"DQ<18>"
$PN"34"81;
"DQ<16>"
$PN"27"82;
"DQ<14>"
$PN"21"83;
"DQ<13>"
$PN"159"84;
"DQ<12>"
$PN"14"85;
"DQ<11>"
$PN"168"86;
"DQ<10>"
$PN"23"87;
"DQ<9>"
$PN"161"88;
"DQ<8>"
$PN"16"32;
"DQ<7>"
$PN"155"33;
"DQ<6>"
$PN"10"34;
"EVENT_N"
$PN"78"23;
"PAR"
$PN"222"46;
"RESET_N"
$PN"58"47;
"RFU<2>"
$PN"144"24;
"SCL"
$PN"141"30;
"SDA"
$PN"285"29;
"VREFCA"
$PN"146"22;
"CK1P"
$PN"218"61;
"BG<0>"
$PN"63"68;
"BG<1>"
$PN"207"69;
"BA<0>"
$PN"81"70;
"SA<0>"
$PN"139"14;
"VDDSPD"
$PN"284"14;
"SA<2>"
$PN"238"16;
"SA<1>"
$PN"140"16;
"DQ<1>"
$PN"150"35;
"DQ<0>"
$PN"5"36;
"ACT_N"
$PN"62"28;
"ALERT_N"
$PN"208"27;
"A2"
$PN"216"71;
"DQ<35>"
$PN"249"107;
"DQ<36>"
$PN"95"108;
"DQ<38>"
$PN"102"109;
"A10"
$PN"225"131;
"A11"
$PN"210"132;
"A14_WE_N"
$PN"228"133;
"A15_CAS_N"
$PN"86"135;
"A16_RAS_N"
$PN"82"136;
"CB<7>"
$PN"199"51;
"ODT<0>"
$PN"87"52;
"ODT<1>"
$PN"91"53;
"CKE<0>"
$PN"60"54;
"S0_N"
$PN"84"62;
"DQ<27>"
$PN"190"89;
"DQ<26>"
$PN"45"90;
"DQ<15>"
$PN"166"91;
"DQ<17>"
$PN"172"92;
"RFU<0>"
$PN"205"25;
"RFU<1>"
$PN"227"26;
"SAVE_N_NC"
$PN"230"31;
"DQ<57>"
$PN"275"144;
"DQ<58>"
$PN"137"145;
"DQ<54>"
$PN"124"146;
"DQ<53>"
$PN"262"147;
"DQ<52>"
$PN"117"148;
"DQ<51>"
$PN"271"149;
"DQ<50>"
$PN"126"150;
"DQ<49>"
$PN"264"110;
"DQ<48>"
$PN"119"111;
"DQ<47>"
$PN"258"112;
"DQ<2>"
$PN"12"37;
"DQ<3>"
$PN"157"38;
"DQ<4>"
$PN"3"39;
"DQ<5>"
$PN"148"40;
%"TAP"
"6","(4100,4300)","2","mstr_standard","I16";
;
HDL_TAP"TRUE"
BODY_TYPE"PLUMBING"
CDS_LIB"mstr_standard";
"B \NAC \NWC"3;
"S \NAC"
BN"12"153;
%"TAP"
"6","(4100,4200)","2","mstr_standard","I17";
;
HDL_TAP"TRUE"
BODY_TYPE"PLUMBING"
CDS_LIB"mstr_standard";
"B \NAC \NWC"3;
"S \NAC"
BN"11"152;
%"PVPP_DEF"
"1","(-1650,2100)","0","mstr_symbols","I172";
;
HDL_POWER"PVPP_DEF"
ROOM"DDR4_CH_B"
BODY_TYPE"PLUMBING"
CDS_LIB"mstr_symbols"
BOM_COST"MEM"
VOLTAGE"2.5V";
"G\NAC"14;
%"CAP_A"
"1","(-1200,1400)","2","dev_discrete","I177";
;
ROOM"DDR4_CH_B"
$SEC"1"
CDS_SEC"1"
CDS_LIB"dev_discrete"
BOM_COST"MEM"
CDS_LOCATION"C6M1"
MATERIAL"X7R"
VOLTAGE"25V"
PACK_TYPE"0402V"
TOLERANCE"10%"
VALUE"0.01UF"
PART_NUMBER"A36096-045"
LOCATION"C6M1";
"B"
$PN"2"15;
"A"
$PN"1"22;
%"GND"
"1","(-1200,1150)","0","mstr_symbols","I178";
;
HDL_POWER"GND"
ROOM"DDR4_CH_B"
BODY_TYPE"PLUMBING"
BOM_COST"MEM"
SIZE"1B"
CDS_LIB"mstr_symbols"
VOLTAGE"0";
"A\NAC"15;
%"TAP"
"6","(4100,4100)","2","mstr_standard","I18";
;
HDL_TAP"TRUE"
BODY_TYPE"PLUMBING"
CDS_LIB"mstr_standard";
"B \NAC \NWC"3;
"S \NAC"
BN"10"151;
%"GND"
"1","(-1350,1775)","0","mstr_symbols","I180";
;
HDL_POWER"GND"
ROOM"DDR4_CH_B"
BODY_TYPE"PLUMBING"
CDS_LIB"mstr_symbols"
SIZE"1B"
BOM_COST"MEM"
VOLTAGE"0";
"A\NAC"16;
%"P12V_NVDIMM_DEF"
"1","(4100,2625)","0","mstr_symbols","I181";
;
HDL_POWER"P12V_NVDIMM_DEF"
BODY_TYPE"PLUMBING"
CDS_LIB"mstr_symbols"
VOLTAGE"12.0";
"G\NAC"17;
%"TAP"
"6","(4350,3950)","2","mstr_standard","I20";
;
HDL_TAP"TRUE"
BODY_TYPE"PLUMBING"
CDS_LIB"mstr_standard";
"B \NAC \NWC"1;
"S \NAC"
BN"9"176;
%"TAP"
"6","(4350,4050)","2","mstr_standard","I21";
;
HDL_TAP"TRUE"
BODY_TYPE"PLUMBING"
CDS_LIB"mstr_standard";
"B \NAC \NWC"1;
"S \NAC"
BN"10"160;
%"TAP"
"6","(4350,3850)","2","mstr_standard","I22";
;
HDL_TAP"TRUE"
BODY_TYPE"PLUMBING"
CDS_LIB"mstr_standard";
"B \NAC \NWC"1;
"S \NAC"
BN"8"175;
%"TAP"
"6","(4350,3750)","2","mstr_standard","I23";
;
HDL_TAP"TRUE"
BODY_TYPE"PLUMBING"
CDS_LIB"mstr_standard";
"B \NAC \NWC"1;
"S \NAC"
BN"7"174;
%"TAP"
"6","(4350,3650)","2","mstr_standard","I24";
;
HDL_TAP"TRUE"
BODY_TYPE"PLUMBING"
CDS_LIB"mstr_standard";
"B \NAC \NWC"1;
"S \NAC"
BN"6"173;
%"TAP"
"6","(4100,4000)","2","mstr_standard","I25";
;
HDL_TAP"TRUE"
BODY_TYPE"PLUMBING"
CDS_LIB"mstr_standard";
"B \NAC \NWC"3;
"S \NAC"
BN"9"122;
%"TAP"
"6","(4100,3900)","2","mstr_standard","I26";
;
HDL_TAP"TRUE"
BODY_TYPE"PLUMBING"
CDS_LIB"mstr_standard";
"B \NAC \NWC"3;
"S \NAC"
BN"8"121;
%"TAP"
"6","(4100,3700)","2","mstr_standard","I27";
;
HDL_TAP"TRUE"
BODY_TYPE"PLUMBING"
CDS_LIB"mstr_standard";
"B \NAC \NWC"3;
"S \NAC"
BN"6"119;
%"TAP"
"6","(4100,3800)","2","mstr_standard","I28";
;
HDL_TAP"TRUE"
BODY_TYPE"PLUMBING"
CDS_LIB"mstr_standard";
"B \NAC \NWC"3;
"S \NAC"
BN"7"120;
%"TAP"
"6","(4100,3600)","2","mstr_standard","I29";
;
HDL_TAP"TRUE"
BODY_TYPE"PLUMBING"
CDS_LIB"mstr_standard";
"B \NAC \NWC"3;
"S \NAC"
BN"5"118;
%"TAP"
"6","(4350,3550)","2","mstr_standard","I30";
;
HDL_TAP"TRUE"
BODY_TYPE"PLUMBING"
CDS_LIB"mstr_standard";
"B \NAC \NWC"1;
"S \NAC"
BN"5"172;
%"TAP"
"6","(4350,3450)","2","mstr_standard","I31";
;
HDL_TAP"TRUE"
BODY_TYPE"PLUMBING"
CDS_LIB"mstr_standard";
"B \NAC \NWC"1;
"S \NAC"
BN"4"171;
%"TAP"
"6","(4350,3350)","2","mstr_standard","I32";
;
HDL_TAP"TRUE"
BODY_TYPE"PLUMBING"
CDS_LIB"mstr_standard";
"B \NAC \NWC"1;
"S \NAC"
BN"3"170;
%"TAP"
"6","(4350,3250)","2","mstr_standard","I33";
;
HDL_TAP"TRUE"
BODY_TYPE"PLUMBING"
CDS_LIB"mstr_standard";
"B \NAC \NWC"1;
"S \NAC"
BN"2"169;
%"TAP"
"6","(4350,3050)","2","mstr_standard","I34";
;
HDL_TAP"TRUE"
BODY_TYPE"PLUMBING"
CDS_LIB"mstr_standard";
"B \NAC \NWC"1;
"S \NAC"
BN"0"159;
%"TAP"
"6","(4350,3150)","2","mstr_standard","I35";
;
HDL_TAP"TRUE"
BODY_TYPE"PLUMBING"
CDS_LIB"mstr_standard";
"B \NAC \NWC"1;
"S \NAC"
BN"1"168;
%"TAP"
"6","(4100,3500)","2","mstr_standard","I36";
;
HDL_TAP"TRUE"
BODY_TYPE"PLUMBING"
CDS_LIB"mstr_standard";
"B \NAC \NWC"3;
"S \NAC"
BN"4"117;
%"TAP"
"6","(4100,3400)","2","mstr_standard","I37";
;
HDL_TAP"TRUE"
BODY_TYPE"PLUMBING"
CDS_LIB"mstr_standard";
"B \NAC \NWC"3;
"S \NAC"
BN"3"116;
%"TAP"
"6","(4100,3300)","2","mstr_standard","I38";
;
HDL_TAP"TRUE"
BODY_TYPE"PLUMBING"
CDS_LIB"mstr_standard";
"B \NAC \NWC"3;
"S \NAC"
BN"2"115;
%"TAP"
"6","(4100,3200)","2","mstr_standard","I39";
;
HDL_TAP"TRUE"
BODY_TYPE"PLUMBING"
CDS_LIB"mstr_standard";
"B \NAC \NWC"3;
"S \NAC"
BN"1"114;
%"TAP"
"6","(4350,4750)","2","mstr_standard","I4";
;
HDL_TAP"TRUE"
BODY_TYPE"PLUMBING"
CDS_LIB"mstr_standard";
"B \NAC \NWC"1;
"S \NAC"
BN"17"167;
%"TAP"
"6","(4100,3100)","2","mstr_standard","I40";
;
HDL_TAP"TRUE"
BODY_TYPE"PLUMBING"
CDS_LIB"mstr_standard";
"B \NAC \NWC"3;
"S \NAC"
BN"0"113;
%"SCONN288_H44441003"
"3","(5250,2050)","0","mstr_sconn","I44";
;
CDS_SEC"3"
ROOM"DDR4_CH_D"
CDS_LOCATION"J6M1"
SEC"3"
SEC_TYPE"PIP"
CDS_LIB"mstr_sconn"
BOM_COST"MEM"
PACK_TYPE"PIP"
MATERIAL"SCONN"
PART_NUMBER"H44441-003"
LOCATION"J6M1";
"VSS<46>"
$PN"147"13;
"VSS<45>"
$PN"149"13;
"VSS<87>"
$PN"15"18;
"VSS<86>"
$PN"17"18;
"VSS<85>"
$PN"20"18;
"VSS<84>"
$PN"22"18;
"VSS<83>"
$PN"24"18;
"VSS<82>"
$PN"26"18;
"VSS<81>"
$PN"28"18;
"VSS<80>"
$PN"31"18;
"VSS<79>"
$PN"33"18;
"VSS<78>"
$PN"35"18;
"VSS<77>"
$PN"37"18;
"VSS<76>"
$PN"39"18;
"VSS<75>"
$PN"42"18;
"VSS<74>"
$PN"44"18;
"VSS<73>"
$PN"46"18;
"VSS<72>"
$PN"48"18;
"VSS<71>"
$PN"50"18;
"VSS<70>"
$PN"53"18;
"VSS<69>"
$PN"55"18;
"VSS<68>"
$PN"57"18;
"VSS<67>"
$PN"94"18;
"VSS<66>"
$PN"96"18;
"VSS<65>"
$PN"98"18;
"VSS<64>"
$PN"101"18;
"VSS<63>"
$PN"103"18;
"VSS<62>"
$PN"105"18;
"VSS<61>"
$PN"107"18;
"VSS<60>"
$PN"109"18;
"VSS<59>"
$PN"112"18;
"VSS<58>"
$PN"114"18;
"VSS<57>"
$PN"116"18;
"VSS<56>"
$PN"118"18;
"VSS<55>"
$PN"120"18;
"VSS<54>"
$PN"123"18;
"VSS<53>"
$PN"125"18;
"VSS<52>"
$PN"127"18;
"VSS<51>"
$PN"129"18;
"VSS<50>"
$PN"131"18;
"VSS<49>"
$PN"134"18;
"VSS<48>"
$PN"136"18;
"VSS<47>"
$PN"138"18;
"VSS<44>"
$PN"151"13;
"VSS<43>"
$PN"154"13;
"VSS<42>"
$PN"156"13;
"VSS<41>"
$PN"158"13;
"VSS<40>"
$PN"160"13;
"VSS<39>"
$PN"162"13;
"VSS<38>"
$PN"165"13;
"VSS<37>"
$PN"167"13;
"VSS<36>"
$PN"169"13;
"VSS<35>"
$PN"171"13;
"VSS<34>"
$PN"173"13;
"VSS<33>"
$PN"176"13;
"VSS<32>"
$PN"178"13;
"VSS<31>"
$PN"180"13;
"VSS<30>"
$PN"182"13;
"VSS<29>"
$PN"184"13;
"VSS<28>"
$PN"187"13;
"VSS<27>"
$PN"189"13;
"VSS<26>"
$PN"191"13;
"VSS<25>"
$PN"193"13;
"VSS<24>"
$PN"195"13;
"VSS<23>"
$PN"198"13;
"VSS<22>"
$PN"200"13;
"VSS<21>"
$PN"202"13;
"VSS<20>"
$PN"239"13;
"VSS<19>"
$PN"241"13;
"VSS<18>"
$PN"243"13;
"VSS<17>"
$PN"246"13;
"VSS<16>"
$PN"248"13;
"VSS<15>"
$PN"250"13;
"VSS<14>"
$PN"252"13;
"VSS<13>"
$PN"254"13;
"VSS<12>"
$PN"257"13;
"VSS<11>"
$PN"259"13;
"VSS<10>"
$PN"261"13;
"VSS<9>"
$PN"263"13;
"VSS<8>"
$PN"265"13;
"VSS<7>"
$PN"268"13;
"VSS<6>"
$PN"270"13;
"VSS<5>"
$PN"272"13;
"VSS<4>"
$PN"274"13;
"VSS<3>"
$PN"276"13;
"VSS<2>"
$PN"279"13;
"VSS<1>"
$PN"281"13;
"VSS<0>"
$PN"283"13;
"VSS<88>"
$PN"13"18;
"VSS<89>"
$PN"11"18;
"VSS<90>"
$PN"9"18;
"VSS<91>"
$PN"6"18;
"VSS<92>"
$PN"4"18;
"VSS<93>"
$PN"2"18;
%"GND"
"1","(4550,750)","2","mstr_symbols","I45";
;
HDL_POWER"GND"
ROOM"DDR4_CH_B"
BODY_TYPE"PLUMBING"
SIZE"1B"
CDS_LIB"mstr_symbols"
BOM_COST"MEM"
VOLTAGE"0";
"A\NAC"18;
%"SCONN288_H44441003"
"2","(3400,3950)","0","mstr_sconn","I46";
;
CDS_SEC"2"
ROOM"DDR4_CH_D"
CDS_LOCATION"J6M1"
SEC"2"
SEC_TYPE"PIP"
CDS_LIB"mstr_sconn"
BOM_COST"MEM"
PACK_TYPE"PIP"
MATERIAL"SCONN"
PART_NUMBER"H44441-003"
LOCATION"J6M1";
"DQS0N"
$PN"152"159;
"DQS0P"
$PN"153"113;
"DQS10N"
$PN"19"160;
"DQS10P"
$PN"18"151;
"DQS11N"
$PN"30"161;
"DQS11P"
$PN"29"152;
"DQS12N"
$PN"41"162;
"DQS12P"
$PN"40"153;
"DQS13N"
$PN"100"163;
"DQS13P"
$PN"99"154;
"DQS14N"
$PN"111"164;
"DQS14P"
$PN"110"155;
"DQS15N"
$PN"122"165;
"DQS15P"
$PN"121"156;
"DQS16N"
$PN"133"166;
"DQS16P"
$PN"132"157;
"DQS17N"
$PN"52"167;
"DQS17P"
$PN"51"158;
"DQS1N"
$PN"163"168;
"DQS1P"
$PN"164"114;
"DQS2N"
$PN"174"169;
"DQS2P"
$PN"175"115;
"DQS3N"
$PN"185"170;
"DQS3P"
$PN"186"116;
"DQS4N"
$PN"244"171;
"DQS4P"
$PN"245"117;
"DQS5N"
$PN"255"172;
"DQS5P"
$PN"256"118;
"DQS6N"
$PN"266"173;
"DQS6P"
$PN"267"119;
"DQS7N"
$PN"277"174;
"DQS7P"
$PN"278"120;
"DQS8N"
$PN"196"175;
"DQS8P"
$PN"197"121;
"DQS9N"
$PN"8"176;
"DQS9P"
$PN"7"122;
%"PVPP_DEF"
"1","(2700,2550)","0","mstr_symbols","I47";
;
HDL_POWER"PVPP_DEF"
ROOM"DDR4_CH_B"
BODY_TYPE"PLUMBING"
CDS_LIB"mstr_symbols"
BOM_COST"MEM"
VOLTAGE"2.5V";
"G\NAC"19;
%"PVTT_DEF"
"1","(2550,2250)","0","mstr_symbols","I48";
;
HDL_POWER"PVTT_DEF"
ROOM"DDR4_CH_B"
BODY_TYPE"PLUMBING"
CDS_LIB"mstr_symbols"
BOM_COST"MEM"
VOLTAGE"0.6V";
"G\NAC"20;
%"PVDDQ_DEF"
"1","(2300,2100)","0","mstr_symbols","I49";
;
HDL_POWER"PVDDQ_DEF"
ROOM"DDR4_CH_B"
BODY_TYPE"PLUMBING"
CDS_LIB"mstr_symbols"
BOM_COST"MEM"
VOLTAGE"1.2V";
"G\NAC"21;
%"TAP"
"6","(4350,4650)","2","mstr_standard","I5";
;
HDL_TAP"TRUE"
BODY_TYPE"PLUMBING"
CDS_LIB"mstr_standard";
"B \NAC \NWC"1;
"S \NAC"
BN"16"166;
%"SCONN288_H44441003"
"4","(3400,1550)","0","mstr_sconn","I50";
;
CDS_SEC"4"
ROOM"DDR4_CH_D"
CDS_LOCATION"J6M1"
SEC"4"
SEC_TYPE"PIP"
CDS_LIB"mstr_sconn"
BOM_COST"MEM"
PACK_TYPE"PIP"
MATERIAL"SCONN"
PART_NUMBER"H44441-003"
LOCATION"J6M1";
"VDD<0>"
$PN"236"21;
"VDD<6>"
$PN"220"21;
"VDD<10>"
$PN"209"21;
"VDD<13>"
$PN"92"21;
"VDD<16>"
$PN"85"21;
"VDD<19>"
$PN"76"21;
"VDD<23>"
$PN"64"21;
"VDD<25>"
$PN"59"21;
"VTT<0>"
$PN"221"20;
"12V<1>"
$PN"1"17;
"12V<0>"
$PN"145"17;
"VDD<24>"
$PN"61"21;
"VDD<22>"
$PN"67"21;
"VDD<21>"
$PN"70"21;
"VDD<20>"
$PN"73"21;
"VDD<18>"
$PN"80"21;
"VDD<17>"
$PN"83"21;
"VDD<15>"
$PN"88"21;
"VDD<14>"
$PN"90"21;
"VDD<12>"
$PN"204"21;
"VDD<11>"
$PN"206"21;
"VDD<9>"
$PN"212"21;
"VDD<8>"
$PN"215"21;
"VDD<7>"
$PN"217"21;
"VDD<5>"
$PN"223"21;
"VDD<4>"
$PN"226"21;
"VDD<3>"
$PN"229"21;
"VDD<2>"
$PN"231"21;
"VDD<1>"
$PN"233"21;
"VPP<4>"
$PN"142"19;
"VPP<3>"
$PN"143"19;
"VPP<2>"
$PN"288"19;
"VPP<1>"
$PN"286"19;
"VPP<0>"
$PN"287"19;
"VTT<1>"
$PN"77"20;
%"TAP"
"6","(1700,4700)","2","mstr_standard","I51";
;
HDL_TAP"TRUE"
BODY_TYPE"PLUMBING"
CDS_LIB"mstr_standard";
"B \NAC \NWC"4;
"S \NAC"
BN"62"138;
%"TAP"
"6","(1700,4600)","2","mstr_standard","I52";
;
HDL_TAP"TRUE"
BODY_TYPE"PLUMBING"
CDS_LIB"mstr_standard";
"B \NAC \NWC"4;
"S \NAC"
BN"60"140;
%"TAP"
"6","(1700,4650)","2","mstr_standard","I53";
;
HDL_TAP"TRUE"
BODY_TYPE"PLUMBING"
CDS_LIB"mstr_standard";
"B \NAC \NWC"4;
"S \NAC"
BN"61"139;
%"TAP"
"6","(1700,4750)","2","mstr_standard","I54";
;
HDL_TAP"TRUE"
BODY_TYPE"PLUMBING"
CDS_LIB"mstr_standard";
"B \NAC \NWC"4;
"S \NAC"
BN"63"137;
%"TAP"
"6","(1700,4350)","2","mstr_standard","I55";
;
HDL_TAP"TRUE"
BODY_TYPE"PLUMBING"
CDS_LIB"mstr_standard";
"B \NAC \NWC"4;
"S \NAC"
BN"55"143;
%"TAP"
"6","(1700,4400)","2","mstr_standard","I56";
;
HDL_TAP"TRUE"
BODY_TYPE"PLUMBING"
CDS_LIB"mstr_standard";
"B \NAC \NWC"4;
"S \NAC"
BN"56"142;
%"TAP"
"6","(1700,4450)","2","mstr_standard","I57";
;
HDL_TAP"TRUE"
BODY_TYPE"PLUMBING"
CDS_LIB"mstr_standard";
"B \NAC \NWC"4;
"S \NAC"
BN"57"144;
%"TAP"
"6","(1700,4550)","2","mstr_standard","I58";
;
HDL_TAP"TRUE"
BODY_TYPE"PLUMBING"
CDS_LIB"mstr_standard";
"B \NAC \NWC"4;
"S \NAC"
BN"59"141;
%"TAP"
"6","(1700,4500)","2","mstr_standard","I59";
;
HDL_TAP"TRUE"
BODY_TYPE"PLUMBING"
CDS_LIB"mstr_standard";
"B \NAC \NWC"4;
"S \NAC"
BN"58"145;
%"TAP"
"6","(4100,4800)","2","mstr_standard","I6";
;
HDL_TAP"TRUE"
BODY_TYPE"PLUMBING"
CDS_LIB"mstr_standard";
"B \NAC \NWC"3;
"S \NAC"
BN"17"158;
%"TAP"
"6","(1700,4200)","2","mstr_standard","I60";
;
HDL_TAP"TRUE"
BODY_TYPE"PLUMBING"
CDS_LIB"mstr_standard";
"B \NAC \NWC"4;
"S \NAC"
BN"52"148;
%"TAP"
"6","(1700,4150)","2","mstr_standard","I61";
;
HDL_TAP"TRUE"
BODY_TYPE"PLUMBING"
CDS_LIB"mstr_standard";
"B \NAC \NWC"4;
"S \NAC"
BN"51"149;
%"TAP"
"6","(1700,4100)","2","mstr_standard","I62";
;
HDL_TAP"TRUE"
BODY_TYPE"PLUMBING"
CDS_LIB"mstr_standard";
"B \NAC \NWC"4;
"S \NAC"
BN"50"150;
%"TAP"
"6","(1700,4250)","2","mstr_standard","I63";
;
HDL_TAP"TRUE"
BODY_TYPE"PLUMBING"
CDS_LIB"mstr_standard";
"B \NAC \NWC"4;
"S \NAC"
BN"53"147;
%"TAP"
"6","(1700,4300)","2","mstr_standard","I64";
;
HDL_TAP"TRUE"
BODY_TYPE"PLUMBING"
CDS_LIB"mstr_standard";
"B \NAC \NWC"4;
"S \NAC"
BN"54"146;
%"TAP"
"6","(200,4700)","0","mstr_standard","I65";
;
HDL_TAP"TRUE"
BODY_TYPE"PLUMBING"
CDS_LIB"mstr_standard";
"B \NAC \NWC"2;
"S \NAC"
BN"16"136;
%"TAP"
"6","(200,4750)","0","mstr_standard","I66";
;
HDL_TAP"TRUE"
BODY_TYPE"PLUMBING"
CDS_LIB"mstr_standard";
"B \NAC \NWC"2;
"S \NAC"
BN"17"134;
%"TAP"
"6","(200,4650)","0","mstr_standard","I67";
;
HDL_TAP"TRUE"
BODY_TYPE"PLUMBING"
CDS_LIB"mstr_standard";
"B \NAC \NWC"2;
"S \NAC"
BN"15"135;
%"TAP"
"6","(200,4600)","0","mstr_standard","I68";
;
HDL_TAP"TRUE"
BODY_TYPE"PLUMBING"
CDS_LIB"mstr_standard";
"B \NAC \NWC"2;
"S \NAC"
BN"14"133;
%"TAP"
"6","(200,4550)","0","mstr_standard","I69";
;
HDL_TAP"TRUE"
BODY_TYPE"PLUMBING"
CDS_LIB"mstr_standard";
"B \NAC \NWC"2;
"S \NAC"
BN"13"124;
%"TAP"
"6","(4100,4600)","2","mstr_standard","I7";
;
HDL_TAP"TRUE"
BODY_TYPE"PLUMBING"
CDS_LIB"mstr_standard";
"B \NAC \NWC"3;
"S \NAC"
BN"15"156;
%"TAP"
"6","(200,4500)","0","mstr_standard","I70";
;
HDL_TAP"TRUE"
BODY_TYPE"PLUMBING"
CDS_LIB"mstr_standard";
"B \NAC \NWC"2;
"S \NAC"
BN"12"123;
%"TAP"
"6","(200,4450)","0","mstr_standard","I71";
;
HDL_TAP"TRUE"
BODY_TYPE"PLUMBING"
CDS_LIB"mstr_standard";
"B \NAC \NWC"2;
"S \NAC"
BN"11"132;
%"TAP"
"6","(200,4400)","0","mstr_standard","I72";
;
HDL_TAP"TRUE"
BODY_TYPE"PLUMBING"
CDS_LIB"mstr_standard";
"B \NAC \NWC"2;
"S \NAC"
BN"10"131;
%"TAP"
"6","(200,4350)","0","mstr_standard","I73";
;
HDL_TAP"TRUE"
BODY_TYPE"PLUMBING"
CDS_LIB"mstr_standard";
"B \NAC \NWC"2;
"S \NAC"
BN"9"130;
%"TAP"
"6","(200,4300)","0","mstr_standard","I74";
;
HDL_TAP"TRUE"
BODY_TYPE"PLUMBING"
CDS_LIB"mstr_standard";
"B \NAC \NWC"2;
"S \NAC"
BN"8"129;
%"TAP"
"6","(200,4250)","0","mstr_standard","I75";
;
HDL_TAP"TRUE"
BODY_TYPE"PLUMBING"
CDS_LIB"mstr_standard";
"B \NAC \NWC"2;
"S \NAC"
BN"7"128;
%"TAP"
"6","(200,4200)","0","mstr_standard","I76";
;
HDL_TAP"TRUE"
BODY_TYPE"PLUMBING"
CDS_LIB"mstr_standard";
"B \NAC \NWC"2;
"S \NAC"
BN"6"127;
%"TAP"
"6","(200,4150)","0","mstr_standard","I77";
;
HDL_TAP"TRUE"
BODY_TYPE"PLUMBING"
CDS_LIB"mstr_standard";
"B \NAC \NWC"2;
"S \NAC"
BN"5"126;
%"TAP"
"6","(200,4100)","0","mstr_standard","I78";
;
HDL_TAP"TRUE"
BODY_TYPE"PLUMBING"
CDS_LIB"mstr_standard";
"B \NAC \NWC"2;
"S \NAC"
BN"4"125;
%"TAP"
"6","(4100,4700)","2","mstr_standard","I8";
;
HDL_TAP"TRUE"
BODY_TYPE"PLUMBING"
CDS_LIB"mstr_standard";
"B \NAC \NWC"3;
"S \NAC"
BN"16"157;
%"TAP"
"6","(1700,3950)","2","mstr_standard","I80";
;
HDL_TAP"TRUE"
BODY_TYPE"PLUMBING"
CDS_LIB"mstr_standard";
"B \NAC \NWC"4;
"S \NAC"
BN"47"112;
%"TAP"
"6","(1700,3850)","2","mstr_standard","I81";
;
HDL_TAP"TRUE"
BODY_TYPE"PLUMBING"
CDS_LIB"mstr_standard";
"B \NAC \NWC"4;
"S \NAC"
BN"45"94;
%"TAP"
"6","(1700,4000)","2","mstr_standard","I82";
;
HDL_TAP"TRUE"
BODY_TYPE"PLUMBING"
CDS_LIB"mstr_standard";
"B \NAC \NWC"4;
"S \NAC"
BN"48"111;
%"TAP"
"6","(1700,4050)","2","mstr_standard","I83";
;
HDL_TAP"TRUE"
BODY_TYPE"PLUMBING"
CDS_LIB"mstr_standard";
"B \NAC \NWC"4;
"S \NAC"
BN"49"110;
%"TAP"
"6","(1700,3900)","2","mstr_standard","I84";
;
HDL_TAP"TRUE"
BODY_TYPE"PLUMBING"
CDS_LIB"mstr_standard";
"B \NAC \NWC"4;
"S \NAC"
BN"46"93;
%"TAP"
"6","(1700,3700)","2","mstr_standard","I85";
;
HDL_TAP"TRUE"
BODY_TYPE"PLUMBING"
CDS_LIB"mstr_standard";
"B \NAC \NWC"4;
"S \NAC"
BN"42"97;
%"TAP"
"6","(1700,3750)","2","mstr_standard","I86";
;
HDL_TAP"TRUE"
BODY_TYPE"PLUMBING"
CDS_LIB"mstr_standard";
"B \NAC \NWC"4;
"S \NAC"
BN"43"96;
%"TAP"
"6","(1700,3800)","2","mstr_standard","I87";
;
HDL_TAP"TRUE"
BODY_TYPE"PLUMBING"
CDS_LIB"mstr_standard";
"B \NAC \NWC"4;
"S \NAC"
BN"44"95;
%"TAP"
"6","(1700,3650)","2","mstr_standard","I88";
;
HDL_TAP"TRUE"
BODY_TYPE"PLUMBING"
CDS_LIB"mstr_standard";
"B \NAC \NWC"4;
"S \NAC"
BN"41"98;
%"TAP"
"6","(1700,3600)","2","mstr_standard","I89";
;
HDL_TAP"TRUE"
BODY_TYPE"PLUMBING"
CDS_LIB"mstr_standard";
"B \NAC \NWC"4;
"S \NAC"
BN"40"99;
%"TAP"
"6","(4350,4550)","2","mstr_standard","I9";
;
HDL_TAP"TRUE"
BODY_TYPE"PLUMBING"
CDS_LIB"mstr_standard";
"B \NAC \NWC"1;
"S \NAC"
BN"15"165;
%"TAP"
"6","(1700,3350)","2","mstr_standard","I90";
;
HDL_TAP"TRUE"
BODY_TYPE"PLUMBING"
CDS_LIB"mstr_standard";
"B \NAC \NWC"4;
"S \NAC"
BN"35"107;
%"TAP"
"6","(1700,3400)","2","mstr_standard","I91";
;
HDL_TAP"TRUE"
BODY_TYPE"PLUMBING"
CDS_LIB"mstr_standard";
"B \NAC \NWC"4;
"S \NAC"
BN"36"108;
%"TAP"
"6","(1700,3500)","2","mstr_standard","I92";
;
HDL_TAP"TRUE"
BODY_TYPE"PLUMBING"
CDS_LIB"mstr_standard";
"B \NAC \NWC"4;
"S \NAC"
BN"38"109;
%"TAP"
"6","(1700,3450)","2","mstr_standard","I93";
;
HDL_TAP"TRUE"
BODY_TYPE"PLUMBING"
CDS_LIB"mstr_standard";
"B \NAC \NWC"4;
"S \NAC"
BN"37"101;
%"TAP"
"6","(1700,3550)","2","mstr_standard","I94";
;
HDL_TAP"TRUE"
BODY_TYPE"PLUMBING"
CDS_LIB"mstr_standard";
"B \NAC \NWC"4;
"S \NAC"
BN"39"100;
%"TAP"
"6","(1700,3200)","2","mstr_standard","I95";
;
HDL_TAP"TRUE"
BODY_TYPE"PLUMBING"
CDS_LIB"mstr_standard";
"B \NAC \NWC"4;
"S \NAC"
BN"32"104;
%"TAP"
"6","(1700,3250)","2","mstr_standard","I96";
;
HDL_TAP"TRUE"
BODY_TYPE"PLUMBING"
CDS_LIB"mstr_standard";
"B \NAC \NWC"4;
"S \NAC"
BN"33"103;
%"TAP"
"6","(1700,3300)","2","mstr_standard","I97";
;
HDL_TAP"TRUE"
BODY_TYPE"PLUMBING"
CDS_LIB"mstr_standard";
"B \NAC \NWC"4;
"S \NAC"
BN"34"102;
%"TAP"
"6","(1700,3100)","2","mstr_standard","I98";
;
HDL_TAP"TRUE"
BODY_TYPE"PLUMBING"
CDS_LIB"mstr_standard";
"B \NAC \NWC"4;
"S \NAC"
BN"30"106;
%"TAP"
"6","(1700,3150)","2","mstr_standard","I99";
;
HDL_TAP"TRUE"
BODY_TYPE"PLUMBING"
CDS_LIB"mstr_standard";
"B \NAC \NWC"4;
"S \NAC"
BN"31"105;
END.
